FILE_TYPE = CONNECTIVITY;
{Allegro Design Entry HDL 16.6-p007 (v16-6-112F) 10/10/2012}
"PAGE_NUMBER" = 245;
0"NC";
1"P3E_CPU0_PE2_SS_C_TXP<15:8>";
2"P3E_CPU0_PE2_SS_C_TXN<15:8>";
3"P3E_CPU0_PE2_SS_RXP<15:8>";
4"P3E_CPU0_PE2_SS_RXN<15:8>";
5"GND\g";
6"GND\g";
7"GND\g";
8"GND\g";
9"GND\g"VOLTAGE"0"CDS_PHYS_NET_NAME"GND"ROOM"TBD"BOM_COST"TBD";
10"CLK_100M_SRC12_DN";
11"USB2_P02_DP";
12"USB2_P02_DN";
13"P3E_CPU0_PE2_SS_RXN<13>";
14"P3E_CPU0_PE2_SS_RXN<14>";
15"P3E_CPU0_PE2_SS_RXN<15>";
16"P3E_CPU0_PE2_SS_RXP<15>";
17"CLK_100M_SRC13_DP";
18"CLK_100M_SRC12_DP";
19"P3E_CPU0_PE2_SS_RXP<13>";
20"P3E_CPU0_PE2_SS_RXN<8>"CDS_PHYS_NET_NAME"P3E_CPU0_PE2_SS_RXN<8>";
21"CLK_100M_SRC13_DN";
22"P3E_CPU0_PE2_SS_RXP<12>";
23"P3E_CPU0_PE2_SS_RXN<12>";
24"P3E_CPU0_PE2_SS_RXP<11>";
25"P3E_CPU0_PE2_SS_RXN<10>";
26"P3E_CPU0_PE2_SS_RXN<9>";
27"P3E_CPU0_PE2_SS_RXP<8>"CDS_PHYS_NET_NAME"P3E_CPU0_PE2_SS_RXP<8>";
28"P3E_CPU0_PE2_SS_RXN<11>";
29"P3E_CPU0_PE2_SS_RXP<10>";
30"P3E_CPU0_PE2_SS_RXP<9>";
31"P3E_CPU0_PE2_SS_C_TXP<8>";
32"P3E_CPU0_PE2_SS_C_TXN<8>";
33"P3E_CPU0_PE2_SS_C_TXP<9>";
34"P3E_CPU0_PE2_SS_C_TXN<9>";
35"P3E_CPU0_PE2_SS_RXP<14>";
36"P3E_CPU0_PE2_SS_C_TXN<15>";
37"P3E_CPU0_PE2_SS_C_TXP<14>";
38"P3E_CPU0_PE2_SS_C_TXP<13>";
39"P3E_CPU0_PE2_SS_C_TXP<10>";
40"P3E_CPU0_PE2_SS_C_TXN<10>";
41"P3E_CPU0_PE2_SS_C_TXP<11>";
42"P3E_CPU0_PE2_SS_C_TXN<11>";
43"P3E_CPU0_PE2_SS_C_TXN<12>";
44"P3E_CPU0_PE2_SS_C_TXP<12>";
45"P3E_CPU0_PE2_SS_C_TXN<13>";
46"P3E_CPU0_PE2_SS_C_TXN<14>";
47"P3E_CPU0_PE2_SS_C_TXP<15>";
%"TAP"
"1","(-5925,2925)","2","mstr_standard","I10";
;
CDS_LIB"mstr_standard"
BODY_TYPE"PLUMBING"
HDL_TAP"TRUE";
"B \NAC \NWC"2;
"S \NAC"
BN"11"42;
%"TAP"
"1","(-5925,3125)","2","mstr_standard","I11";
;
CDS_LIB"mstr_standard"
BODY_TYPE"PLUMBING"
HDL_TAP"TRUE";
"B \NAC \NWC"2;
"S \NAC"
BN"10"40;
%"TAP"
"1","(-5925,3275)","2","mstr_standard","I12";
;
CDS_LIB"mstr_standard"
BODY_TYPE"PLUMBING"
HDL_TAP"TRUE";
"B \NAC \NWC"2;
"S \NAC"
BN"9"34;
%"TAP"
"1","(-5300,2525)","2","mstr_standard","I13";
;
CDS_LIB"mstr_standard"
BODY_TYPE"PLUMBING"
HDL_TAP"TRUE";
"B \NAC \NWC"1;
"S \NAC"
BN"14"37;
%"TAP"
"1","(-5300,2775)","2","mstr_standard","I14";
;
CDS_LIB"mstr_standard"
BODY_TYPE"PLUMBING"
HDL_TAP"TRUE";
"B \NAC \NWC"1;
"S \NAC"
BN"12"44;
%"TAP"
"1","(-5300,2625)","2","mstr_standard","I15";
;
CDS_LIB"mstr_standard"
BODY_TYPE"PLUMBING"
HDL_TAP"TRUE";
"B \NAC \NWC"1;
"S \NAC"
BN"13"38;
%"TAP"
"1","(-5300,2975)","2","mstr_standard","I16";
;
CDS_LIB"mstr_standard"
BODY_TYPE"PLUMBING"
HDL_TAP"TRUE";
"B \NAC \NWC"1;
"S \NAC"
BN"11"41;
%"TAP"
"1","(-5300,3075)","2","mstr_standard","I17";
;
CDS_LIB"mstr_standard"
BODY_TYPE"PLUMBING"
HDL_TAP"TRUE";
"B \NAC \NWC"1;
"S \NAC"
BN"10"39;
%"TAP"
"1","(-5300,3225)","2","mstr_standard","I18";
;
CDS_LIB"mstr_standard"
BODY_TYPE"PLUMBING"
HDL_TAP"TRUE";
"B \NAC \NWC"1;
"S \NAC"
BN"9"33;
%"GND"
"1","(-4750,1825)","0","mstr_symbols","I19";
;
ROOM"PVPP_KLM_VR"
SIZE"1B"
VOLTAGE"0"
BOM_COST"PVPP_KLM_VR"
CDS_LIB"mstr_symbols"
BODY_TYPE"PLUMBING"
HDL_POWER"GND";
"A\NAC"5;
%"GND"
"1","(-4300,1625)","0","mstr_symbols","I20";
;
BOM_COST"PVPP_KLM_VR"
VOLTAGE"0"
SIZE"1B"
ROOM"PVPP_KLM_VR"
CDS_LIB"mstr_symbols"
BODY_TYPE"PLUMBING"
HDL_POWER"GND";
"A\NAC"6;
%"TAP"
"1","(-5925,3375)","2","mstr_standard","I23";
;
CDS_LIB"mstr_standard"
BODY_TYPE"PLUMBING"
HDL_TAP"TRUE";
"B \NAC \NWC"2;
"S \NAC"
BN"8"32;
%"TAP"
"1","(-5300,3425)","2","mstr_standard","I24";
;
CDS_LIB"mstr_standard"
BODY_TYPE"PLUMBING"
HDL_TAP"TRUE";
"B \NAC \NWC"1;
"S \NAC"
BN"8"31;
%"GND"
"1","(-4450,3575)","0","mstr_symbols","I25";
;
CDS_LIB"mstr_symbols"
ROOM"PVPP_KLM_VR"
SIZE"1B"
VOLTAGE"0"
BOM_COST"PVPP_KLM_VR"
BODY_TYPE"PLUMBING"
HDL_POWER"GND";
"A\NAC"7;
%"GND"
"1","(-3700,1625)","0","mstr_symbols","I26";
;
BOM_COST"PVPP_KLM_VR"
VOLTAGE"0"
SIZE"1B"
ROOM"PVPP_KLM_VR"
CDS_LIB"mstr_symbols"
BODY_TYPE"PLUMBING"
HDL_POWER"GND";
"A\NAC"8;
%"GND"
"1","(-3400,1625)","0","mstr_symbols","I27";
;
BOM_COST"PVPP_KLM_VR"
VOLTAGE"0"
SIZE"1B"
ROOM"PVPP_KLM_VR"
CDS_LIB"mstr_symbols"
BODY_TYPE"PLUMBING"
HDL_POWER"GND";
"A\NAC"9;
%"TAP"
"6","(-2500,2325)","2","mstr_standard","I29";
;
CDS_LIB"mstr_standard"
BODY_TYPE"PLUMBING"
HDL_TAP"TRUE";
"B \NAC \NWC"4;
"S \NAC"
BN"15"15;
%"TAP"
"6","(-2300,2275)","2","mstr_standard","I30";
;
CDS_LIB"mstr_standard"
BODY_TYPE"PLUMBING"
HDL_TAP"TRUE";
"B \NAC \NWC"3;
"S \NAC"
BN"15"16;
%"TAP"
"6","(-2500,2575)","2","mstr_standard","I31";
;
CDS_LIB"mstr_standard"
BODY_TYPE"PLUMBING"
HDL_TAP"TRUE";
"B \NAC \NWC"4;
"S \NAC"
BN"13"13;
%"TAP"
"6","(-2500,2475)","2","mstr_standard","I32";
;
CDS_LIB"mstr_standard"
BODY_TYPE"PLUMBING"
HDL_TAP"TRUE";
"B \NAC \NWC"4;
"S \NAC"
BN"14"14;
%"TAP"
"6","(-2500,2775)","2","mstr_standard","I33";
;
CDS_LIB"mstr_standard"
BODY_TYPE"PLUMBING"
HDL_TAP"TRUE";
"B \NAC \NWC"4;
"S \NAC"
BN"12"23;
%"TAP"
"6","(-2500,2925)","2","mstr_standard","I34";
;
CDS_LIB"mstr_standard"
BODY_TYPE"PLUMBING"
HDL_TAP"TRUE";
"B \NAC \NWC"4;
"S \NAC"
BN"11"28;
%"TAP"
"6","(-2500,3075)","2","mstr_standard","I35";
;
CDS_LIB"mstr_standard"
BODY_TYPE"PLUMBING"
HDL_TAP"TRUE";
"B \NAC \NWC"4;
"S \NAC"
BN"10"25;
%"TAP"
"6","(-2500,3225)","2","mstr_standard","I36";
;
CDS_LIB"mstr_standard"
BODY_TYPE"PLUMBING"
HDL_TAP"TRUE";
"B \NAC \NWC"4;
"S \NAC"
BN"9"26;
%"TAP"
"6","(-2300,2425)","2","mstr_standard","I37";
;
CDS_LIB"mstr_standard"
BODY_TYPE"PLUMBING"
HDL_TAP"TRUE";
"B \NAC \NWC"3;
"S \NAC"
BN"14"35;
%"TAP"
"6","(-2300,2725)","2","mstr_standard","I38";
;
CDS_LIB"mstr_standard"
BODY_TYPE"PLUMBING"
HDL_TAP"TRUE";
"B \NAC \NWC"3;
"S \NAC"
BN"12"22;
%"TAP"
"6","(-2300,2625)","2","mstr_standard","I39";
;
CDS_LIB"mstr_standard"
BODY_TYPE"PLUMBING"
HDL_TAP"TRUE";
"B \NAC \NWC"3;
"S \NAC"
BN"13"19;
%"TAP"
"6","(-2300,3025)","2","mstr_standard","I40";
;
CDS_LIB"mstr_standard"
BODY_TYPE"PLUMBING"
HDL_TAP"TRUE";
"B \NAC \NWC"3;
"S \NAC"
BN"10"29;
%"TAP"
"6","(-2300,2875)","2","mstr_standard","I41";
;
CDS_LIB"mstr_standard"
BODY_TYPE"PLUMBING"
HDL_TAP"TRUE";
"B \NAC \NWC"3;
"S \NAC"
BN"11"24;
%"TAP"
"6","(-2300,3175)","2","mstr_standard","I42";
;
CDS_LIB"mstr_standard"
BODY_TYPE"PLUMBING"
HDL_TAP"TRUE";
"B \NAC \NWC"3;
"S \NAC"
BN"9"30;
%"TAP"
"6","(-2300,3325)","2","mstr_standard","I43";
;
CDS_LIB"mstr_standard"
BODY_TYPE"PLUMBING"
HDL_TAP"TRUE";
"B \NAC \NWC"3;
"S \NAC"
BN"8"27;
%"TAP"
"6","(-2500,3375)","2","mstr_standard","I44";
;
CDS_LIB"mstr_standard"
BODY_TYPE"PLUMBING"
HDL_TAP"TRUE";
"B \NAC \NWC"4;
"S \NAC"
BN"8"20;
%"SMC-CONN60A-22-GP"
"1","(-4025,2775)","0","w_hdl","I48";
;
PACK_TYPE"CONN-G7"
PART_NUMBER"020.C0082.0060"
CDS_LIB"w_hdl"
CDS_LMAN_SYM_OUTLINE"-100,900,100,-900"
CDS_LOCATION"CONX8"
$SEC"1"
CDS_SEC"1"
LOCATION"CONX8"
VALUE"SMC-CONN60A-22-GP";
"PTH2"
$PN"PTH2"6;
"PTH1"
$PN"PTH1"7;
"NP2"
$PN"NP2"8;
"NP1"
$PN"NP1"7;
"60"
$PN"60"0;
"58"
$PN"58"9;
"56"
$PN"56"21;
"54"
$PN"54"17;
"52"
$PN"52"9;
"50"
$PN"50"16;
"48"
$PN"48"15;
"46"
$PN"46"9;
"44"
$PN"44"35;
"42"
$PN"42"14;
"40"
$PN"40"9;
"38"
$PN"38"13;
"36"
$PN"36"19;
"34"
$PN"34"9;
"32"
$PN"32"22;
"30"
$PN"30"23;
"28"
$PN"28"9;
"26"
$PN"26"24;
"24"
$PN"24"28;
"22"
$PN"22"9;
"20"
$PN"20"29;
"18"
$PN"18"25;
"16"
$PN"16"9;
"14"
$PN"14"30;
"12"
$PN"12"26;
"10"
$PN"10"9;
"59"
$PN"59"12;
"57"
$PN"57"11;
"55"
$PN"55"5;
"53"
$PN"53"10;
"51"
$PN"51"18;
"49"
$PN"49"5;
"47"
$PN"47"47;
"45"
$PN"45"36;
"43"
$PN"43"5;
"41"
$PN"41"46;
"39"
$PN"39"37;
"37"
$PN"37"5;
"35"
$PN"35"38;
"33"
$PN"33"45;
"31"
$PN"31"5;
"29"
$PN"29"44;
"27"
$PN"27"43;
"25"
$PN"25"5;
"23"
$PN"23"42;
"21"
$PN"21"41;
"19"
$PN"19"5;
"17"
$PN"17"39;
"15"
$PN"15"40;
"13"
$PN"13"5;
"11"
$PN"11"33;
"9"
$PN"9"34;
"8"
$PN"8"27;
"6"
$PN"6"20;
"4"
$PN"4"9;
"2"
$PN"2"0;
"7"
$PN"7"5;
"5"
$PN"5"32;
"3"
$PN"3"31;
"1"
$PN"1"5;
%"TAP"
"1","(-5300,2325)","2","mstr_standard","I5";
;
CDS_LIB"mstr_standard"
BODY_TYPE"PLUMBING"
HDL_TAP"TRUE";
"B \NAC \NWC"1;
"S \NAC"
BN"15"47;
%"TAP"
"1","(-5925,2375)","2","mstr_standard","I6";
;
CDS_LIB"mstr_standard"
BODY_TYPE"PLUMBING"
HDL_TAP"TRUE";
"B \NAC \NWC"2;
"S \NAC"
BN"15"36;
%"TAP"
"1","(-5925,2475)","2","mstr_standard","I7";
;
CDS_LIB"mstr_standard"
BODY_TYPE"PLUMBING"
HDL_TAP"TRUE";
"B \NAC \NWC"2;
"S \NAC"
BN"14"46;
%"TAP"
"1","(-5925,2825)","2","mstr_standard","I8";
;
CDS_LIB"mstr_standard"
BODY_TYPE"PLUMBING"
HDL_TAP"TRUE";
"B \NAC \NWC"2;
"S \NAC"
BN"12"43;
%"TAP"
"1","(-5925,2675)","2","mstr_standard","I9";
;
CDS_LIB"mstr_standard"
BODY_TYPE"PLUMBING"
HDL_TAP"TRUE";
"B \NAC \NWC"2;
"S \NAC"
BN"13"45;
END.
